(kicad_pcb
	(version 20260206)
	(generator "pcbnew")
	(generator_version "10.0")
	(general
		(thickness 1.6)
		(legacy_teardrops no)
	)
	(paper "A4")
	(title_block
		(title "Bryce Canyon_F.DPB_16315-1-OCP.brd")
		(comment 1 "Bryce Canyon / footprint 1805 of 2223 (MONO4), pads 148-166 of 166")
	)
	(layers
		(0 "F.Cu" signal "TOP")
		(4 "In1.Cu" signal "L2GND")
		(6 "In2.Cu" signal "L3")
		(8 "In3.Cu" signal "L4GND")
		(10 "In4.Cu" signal "L5")
		(12 "In5.Cu" signal "L6VCC")
		(14 "In6.Cu" signal "L7VCC")
		(16 "In7.Cu" signal "L8")
		(18 "In8.Cu" signal "L9GND")
		(20 "In9.Cu" signal "L10")
		(22 "In10.Cu" signal "L11GND")
		(2 "B.Cu" signal "BOTTOM")
		(9 "F.Adhes" user "F.Adhesive")
		(11 "B.Adhes" user "B.Adhesive")
		(13 "F.Paste" user "Package Geometry/Pastemask Top")
		(15 "B.Paste" user "Package Geometry/Pastemask Bottom")
		(5 "F.SilkS" user "Ref Des/Silkscreen Top")
		(7 "B.SilkS" user "Ref Des/Silkscreen Bottom")
		(1 "F.Mask" user "Board Geometry/Soldermask Top")
		(3 "B.Mask" user "Board Geometry/Soldermask Bottom")
		(17 "Dwgs.User" user "User.Drawings")
		(19 "Cmts.User" user "User.Comments")
		(21 "Eco1.User" user "User.Eco1")
		(23 "Eco2.User" user "User.Eco2")
		(25 "Edge.Cuts" user "Board Geometry/Outline")
		(27 "Margin" user)
		(31 "F.CrtYd" user "Package Geometry/Place Bound Top")
		(29 "B.CrtYd" user "Package Geometry/Place Bound Bottom")
		(35 "F.Fab" user "Ref Des/Assembly Top")
		(33 "B.Fab" user "Ref Des/Assembly Bottom")
	)
	(footprint ""
		(layer "F.Cu")
		(at 281.999944 -14.85011 90)
		(property "Reference" "MONO4"
			(at 0 0 90)
			(layer "F.SilkS")
			(hide yes)
			(effects
				(font
					(size 1.27 1.27)
				)
			)
		)
		(property "Value" "AMP-CONN164-4R-1-GP"
			(at -25.705054 -1.203706 90)
			(unlocked yes)
			(layer "F.Fab")
			(hide yes)
			(effects
				(font
					(size 1.016 1.016)
					(thickness 0.1524)
				)
			)
		)
		(property "Device Type" "PREFIT-164P-890091-1H441"
			(at -25.705054 -2.727706 90)
			(unlocked yes)
			(layer "F.Fab")
			(hide yes)
			(effects
				(font
					(size 1.016 1.016)
					(thickness 0.1524)
				)
			)
		)
		(duplicate_pad_numbers_are_jumpers no)
		(pad "B64" thru_hole circle
			(at 53.349906 3.24993 90)
			(size 1.0668 1.0668)
			(drill 0.719836)
			(layers "*.Cu" "*.Mask")
			(remove_unused_layers no)
			(net "PCIE_COMP_B_TO_IOM_B_19_DN")
			(clearance 0.1905)
			(thermal_gap 0.1905)
		)
		(pad "B65" thru_hole circle
			(at 54.349904 1.249934 90)
			(size 1.0668 1.0668)
			(drill 0.719836)
			(layers "*.Cu" "*.Mask")
			(remove_unused_layers no)
			(net "GND")
			(clearance 0.1905)
			(thermal_gap 0.1905)
		)
		(pad "B66" thru_hole circle
			(at 55.349902 3.24993 90)
			(size 1.0668 1.0668)
			(drill 0.719836)
			(layers "*.Cu" "*.Mask")
			(remove_unused_layers no)
			(net "GND")
			(clearance 0.1905)
			(thermal_gap 0.1905)
		)
		(pad "B67" thru_hole circle
			(at 56.3499 1.249934 90)
			(size 1.0668 1.0668)
			(drill 0.719836)
			(layers "*.Cu" "*.Mask")
			(remove_unused_layers no)
			(net "PCIE_COMP_B_TO_IOM_B_20_DP")
			(clearance 0.1905)
			(thermal_gap 0.1905)
		)
		(pad "B68" thru_hole circle
			(at 57.349898 3.24993 90)
			(size 1.0668 1.0668)
			(drill 0.719836)
			(layers "*.Cu" "*.Mask")
			(remove_unused_layers no)
			(net "PCIE_COMP_B_TO_IOM_B_20_DN")
			(clearance 0.1905)
			(thermal_gap 0.1905)
		)
		(pad "B69" thru_hole circle
			(at 58.349896 1.249934 90)
			(size 1.0668 1.0668)
			(drill 0.719836)
			(layers "*.Cu" "*.Mask")
			(remove_unused_layers no)
			(net "GND")
			(clearance 0.1905)
			(thermal_gap 0.1905)
		)
		(pad "B70" thru_hole circle
			(at 59.349894 3.24993 90)
			(size 1.0668 1.0668)
			(drill 0.719836)
			(layers "*.Cu" "*.Mask")
			(remove_unused_layers no)
			(net "GND")
			(clearance 0.1905)
			(thermal_gap 0.1905)
		)
		(pad "B71" thru_hole circle
			(at 60.349892 1.249934 90)
			(size 1.0668 1.0668)
			(drill 0.719836)
			(layers "*.Cu" "*.Mask")
			(remove_unused_layers no)
			(net "PCIE_COMP_B_TO_IOM_B_21_DP")
			(clearance 0.1905)
			(thermal_gap 0.1905)
		)
		(pad "B72" thru_hole circle
			(at 61.34989 3.24993 90)
			(size 1.0668 1.0668)
			(drill 0.719836)
			(layers "*.Cu" "*.Mask")
			(remove_unused_layers no)
			(net "PCIE_COMP_B_TO_IOM_B_21_DN")
			(clearance 0.1905)
			(thermal_gap 0.1905)
		)
		(pad "B73" thru_hole circle
			(at 62.349888 1.249934 90)
			(size 1.0668 1.0668)
			(drill 0.719836)
			(layers "*.Cu" "*.Mask")
			(remove_unused_layers no)
			(net "GND")
			(clearance 0.1905)
			(thermal_gap 0.1905)
		)
		(pad "B74" thru_hole circle
			(at 63.349886 3.24993 90)
			(size 1.0668 1.0668)
			(drill 0.719836)
			(layers "*.Cu" "*.Mask")
			(remove_unused_layers no)
			(net "GND")
			(clearance 0.1905)
			(thermal_gap 0.1905)
		)
		(pad "B75" thru_hole circle
			(at 64.349884 1.249934 90)
			(size 1.0668 1.0668)
			(drill 0.719836)
			(layers "*.Cu" "*.Mask")
			(remove_unused_layers no)
			(net "PCIE_COMP_B_TO_IOM_B_22_DP")
			(clearance 0.1905)
			(thermal_gap 0.1905)
		)
		(pad "B76" thru_hole circle
			(at 65.349882 3.24993 90)
			(size 1.0668 1.0668)
			(drill 0.719836)
			(layers "*.Cu" "*.Mask")
			(remove_unused_layers no)
			(net "PCIE_COMP_B_TO_IOM_B_22_DN")
			(clearance 0.1905)
			(thermal_gap 0.1905)
		)
		(pad "B77" thru_hole circle
			(at 66.34988 1.249934 90)
			(size 1.0668 1.0668)
			(drill 0.719836)
			(layers "*.Cu" "*.Mask")
			(remove_unused_layers no)
			(net "GND")
			(clearance 0.1905)
			(thermal_gap 0.1905)
		)
		(pad "B78" thru_hole circle
			(at 67.349878 3.24993 90)
			(size 1.0668 1.0668)
			(drill 0.719836)
			(layers "*.Cu" "*.Mask")
			(remove_unused_layers no)
			(net "GND")
			(clearance 0.1905)
			(thermal_gap 0.1905)
		)
		(pad "B79" thru_hole circle
			(at 68.349876 1.249934 90)
			(size 1.0668 1.0668)
			(drill 0.719836)
			(layers "*.Cu" "*.Mask")
			(remove_unused_layers no)
			(net "PCIE_COMP_B_TO_IOM_B_23_DP")
			(clearance 0.1905)
			(thermal_gap 0.1905)
		)
		(pad "B80" thru_hole circle
			(at 69.349874 3.24993 90)
			(size 1.0668 1.0668)
			(drill 0.719836)
			(layers "*.Cu" "*.Mask")
			(remove_unused_layers no)
			(net "PCIE_COMP_B_TO_IOM_B_23_DN")
			(clearance 0.1905)
			(thermal_gap 0.1905)
		)
		(pad "B81" thru_hole circle
			(at 70.350126 1.249934 90)
			(size 1.0668 1.0668)
			(drill 0.719836)
			(layers "*.Cu" "*.Mask")
			(remove_unused_layers no)
			(net "GND")
			(clearance 0.1905)
			(thermal_gap 0.1905)
		)
		(pad "B82" thru_hole circle
			(at 71.350124 3.24993 90)
			(size 1.0668 1.0668)
			(drill 0.719836)
			(layers "*.Cu" "*.Mask")
			(remove_unused_layers no)
			(net "COMP_B_POWER_FAIL_N")
			(clearance 0.1905)
			(thermal_gap 0.1905)
		)
	)
)
